(kicad_pcb
	(version 20260206)
	(generator "pcbnew")
	(generator_version "10.0")
	(general
		(thickness 1.6)
		(legacy_teardrops no)
	)
	(paper "A4")
	(title_block
		(title "Bryce Canyon_IOM_M2_16342-2_OCP.brd")
		(comment 1 "Bryce Canyon / footprints 364-370 of 1146")
	)
	(layers
		(0 "F.Cu" signal "TOP")
		(4 "In1.Cu" signal "L2GND")
		(6 "In2.Cu" signal "L3")
		(8 "In3.Cu" signal "L4VCC")
		(10 "In4.Cu" signal "L5VCC")
		(12 "In5.Cu" signal "L6")
		(14 "In6.Cu" signal "L7GND")
		(2 "B.Cu" signal "BOTTOM")
		(9 "F.Adhes" user "F.Adhesive")
		(11 "B.Adhes" user "B.Adhesive")
		(13 "F.Paste" user "Package Geometry/Pastemask Top")
		(15 "B.Paste" user "Package Geometry/Pastemask Bottom")
		(5 "F.SilkS" user "Ref Des/Silkscreen Top")
		(7 "B.SilkS" user "Ref Des/Silkscreen Bottom")
		(1 "F.Mask" user "Board Geometry/Soldermask Top")
		(3 "B.Mask" user "Board Geometry/Soldermask Bottom")
		(17 "Dwgs.User" user "User.Drawings")
		(19 "Cmts.User" user "User.Comments")
		(21 "Eco1.User" user "User.Eco1")
		(23 "Eco2.User" user "User.Eco2")
		(25 "Edge.Cuts" user "Board Geometry/Outline")
		(27 "Margin" user)
		(31 "F.CrtYd" user "Package Geometry/Place Bound Top")
		(29 "B.CrtYd" user "Package Geometry/Place Bound Bottom")
		(35 "F.Fab" user "Ref Des/Assembly Top")
		(33 "B.Fab" user "Ref Des/Assembly Bottom")
	)
	(footprint ""
		(layer "F.Cu")
		(at 83.358228 -82.136996 90)
		(property "Reference" "VIA12"
			(at 0 0 90)
			(layer "F.SilkS")
			(hide yes)
			(effects
				(font
					(size 1.27 1.27)
				)
			)
		)
		(property "Value" "85OHM-8L-1D6MM-L16L18-GP"
			(at 4.064 0.6096 90)
			(unlocked yes)
			(layer "F.Fab")
			(hide yes)
			(effects
				(font
					(size 1.016 1.016)
					(thickness 0.1524)
				)
			)
		)
		(property "Device Type" "VIA-PCIE-4P-368076"
			(at 4.064 -0.9144 90)
			(unlocked yes)
			(layer "F.Fab")
			(hide yes)
			(effects
				(font
					(size 1.016 1.016)
					(thickness 0.1524)
				)
			)
		)
		(duplicate_pad_numbers_are_jumpers no)
		(fp_rect
			(start -1.8415 0.381)
			(end 1.8415 -0.381)
			(stroke
				(width 0)
				(type default)
			)
			(fill no)
			(layer "F.CrtYd")
		)
		(fp_rect
			(start -1.8415 0.381)
			(end 1.8415 -0.381)
			(stroke
				(width 0)
				(type default)
			)
			(fill no)
			(layer "F.Fab")
		)
		(pad "1" thru_hole circle
			(at -1.4605 0 90)
			(size 0.508 0.508)
			(drill 0.254)
			(layers "*.Cu" "*.Mask")
			(remove_unused_layers no)
			(net "GND")
			(clearance 0.127)
			(thermal_gap 0.127)
		)
		(pad "2" thru_hole circle
			(at -0.4445 0 90)
			(size 0.508 0.508)
			(drill 0.254)
			(layers "*.Cu" "*.Mask")
			(remove_unused_layers no)
			(net "PCIE_IOM_TO_COMP_19_DP")
			(clearance 0.127)
			(thermal_gap 0.127)
		)
		(pad "3" thru_hole circle
			(at 0.4445 0 90)
			(size 0.508 0.508)
			(drill 0.254)
			(layers "*.Cu" "*.Mask")
			(remove_unused_layers no)
			(net "PCIE_IOM_TO_COMP_19_DN")
			(clearance 0.127)
			(thermal_gap 0.127)
		)
		(pad "4" thru_hole circle
			(at 1.4605 0 90)
			(size 0.508 0.508)
			(drill 0.254)
			(layers "*.Cu" "*.Mask")
			(remove_unused_layers no)
			(net "GND")
			(clearance 0.127)
			(thermal_gap 0.127)
		)
	)
	(footprint ""
		(layer "F.Cu")
		(at 74.14133 -136.980676 90)
		(property "Reference" "C27"
			(at 0 0 90)
			(layer "F.SilkS")
			(hide yes)
			(effects
				(font
					(size 1.27 1.27)
				)
			)
		)
		(property "Value" "SCD1U16V2KX-3GP"
			(at 1.1811 -2.7051 90)
			(unlocked yes)
			(layer "F.Fab")
			(hide yes)
			(effects
				(font
					(size 1.016 1.016)
					(thickness 0.1524)
				)
			)
		)
		(property "Device Type" "C402H22"
			(at 1.1811 -4.2291 90)
			(unlocked yes)
			(layer "F.Fab")
			(hide yes)
			(effects
				(font
					(size 1.016 1.016)
					(thickness 0.1524)
				)
			)
		)
		(duplicate_pad_numbers_are_jumpers no)
		(fp_rect
			(start -0.4318 0.9525)
			(end 0.4318 -0.9525)
			(stroke
				(width 0)
				(type default)
			)
			(fill no)
			(layer "F.CrtYd")
		)
		(fp_rect
			(start -0.4318 0.9525)
			(end 0.4318 -0.9525)
			(stroke
				(width 0)
				(type default)
			)
			(fill no)
			(layer "F.Fab")
		)
		(pad "1" smd custom
			(at 0 -0.4445 90)
			(size 0.1524 0.1524)
			(layers "F.Cu" "F.Mask" "F.Paste")
			(net "P3V3_STBY")
			(options
				(clearance outline)
				(anchor circle)
			)
			(primitives
				(gr_poly
					(pts
						(arc
							(start 0.3048 -0.2032)
							(mid 0.275042 -0.275042)
							(end 0.2032 -0.3048)
						)
						(arc
							(start -0.2032 -0.3048)
							(mid -0.275042 -0.275042)
							(end -0.3048 -0.2032)
						)
						(arc
							(start -0.3048 0.2032)
							(mid -0.275042 0.275042)
							(end -0.2032 0.3048)
						)
						(arc
							(start 0.2032 0.3048)
							(mid 0.275042 0.275042)
							(end 0.3048 0.2032)
						)
					)
					(width 0)
					(fill yes)
				)
			)
		)
		(pad "2" smd custom
			(at 0 0.4445 90)
			(size 0.1524 0.1524)
			(layers "F.Cu" "F.Mask" "F.Paste")
			(net "GND")
			(options
				(clearance outline)
				(anchor circle)
			)
			(primitives
				(gr_poly
					(pts
						(arc
							(start 0.3048 -0.2032)
							(mid 0.275042 -0.275042)
							(end 0.2032 -0.3048)
						)
						(arc
							(start -0.2032 -0.3048)
							(mid -0.275042 -0.275042)
							(end -0.3048 -0.2032)
						)
						(arc
							(start -0.3048 0.2032)
							(mid -0.275042 0.275042)
							(end -0.2032 0.3048)
						)
						(arc
							(start 0.2032 0.3048)
							(mid 0.275042 0.275042)
							(end 0.3048 0.2032)
						)
					)
					(width 0)
					(fill yes)
				)
			)
		)
	)
	(footprint ""
		(layer "F.Cu")
		(at 14.478 -11.43 -90)
		(property "Reference" "R47"
			(at 0 0 270)
			(layer "F.SilkS")
			(hide yes)
			(effects
				(font
					(size 1.27 1.27)
				)
			)
		)
		(property "Value" "1MR2F-GP"
			(at 0.064008 -3.993896 270)
			(unlocked yes)
			(layer "F.Fab")
			(hide yes)
			(effects
				(font
					(size 1.016 1.016)
					(thickness 0.1524)
				)
			)
		)
		(property "Device Type" "R402H16"
			(at 0.064008 -5.517896 270)
			(unlocked yes)
			(layer "F.Fab")
			(hide yes)
			(effects
				(font
					(size 1.016 1.016)
					(thickness 0.1524)
				)
			)
		)
		(duplicate_pad_numbers_are_jumpers no)
		(fp_line
			(start -0.508 -0.9398)
			(end -0.508 0.9398)
			(stroke
				(width 0.1524)
				(type default)
			)
			(layer "F.SilkS")
		)
		(fp_line
			(start 0.508 -0.9398)
			(end -0.508 -0.9398)
			(stroke
				(width 0.1524)
				(type default)
			)
			(layer "F.SilkS")
		)
		(fp_rect
			(start -0.508 0.9398)
			(end 0.508 -0.9398)
			(stroke
				(width 0)
				(type default)
			)
			(fill no)
			(layer "F.CrtYd")
		)
		(fp_rect
			(start -0.508 0.9398)
			(end 0.508 -0.9398)
			(stroke
				(width 0)
				(type default)
			)
			(fill no)
			(layer "F.Fab")
		)
		(pad "1" smd custom
			(at 0 -0.4445 270)
			(size 0.1397 0.1397)
			(layers "F.Cu" "F.Mask" "F.Paste")
			(net "RST_BTN_GND")
			(options
				(clearance outline)
				(anchor circle)
			)
			(primitives
				(gr_poly
					(pts
						(arc
							(start -0.1778 -0.2794)
							(mid -0.249642 -0.249642)
							(end -0.2794 -0.1778)
						)
						(arc
							(start -0.2794 0.1778)
							(mid -0.249642 0.249642)
							(end -0.1778 0.2794)
						)
						(arc
							(start 0.1778 0.2794)
							(mid 0.249642 0.249642)
							(end 0.2794 0.1778)
						)
						(arc
							(start 0.2794 -0.1778)
							(mid 0.249642 -0.249642)
							(end 0.1778 -0.2794)
						)
					)
					(width 0)
					(fill yes)
				)
			)
		)
		(pad "2" smd custom
			(at 0 0.4445 270)
			(size 0.1397 0.1397)
			(layers "F.Cu" "F.Mask" "F.Paste")
			(net "GND")
			(options
				(clearance outline)
				(anchor circle)
			)
			(primitives
				(gr_poly
					(pts
						(arc
							(start -0.1778 -0.2794)
							(mid -0.249642 -0.249642)
							(end -0.2794 -0.1778)
						)
						(arc
							(start -0.2794 0.1778)
							(mid -0.249642 0.249642)
							(end -0.1778 0.2794)
						)
						(arc
							(start 0.1778 0.2794)
							(mid 0.249642 0.249642)
							(end 0.2794 0.1778)
						)
						(arc
							(start 0.2794 -0.1778)
							(mid 0.249642 -0.249642)
							(end 0.1778 -0.2794)
						)
					)
					(width 0)
					(fill yes)
				)
			)
		)
	)
	(footprint ""
		(layer "F.Cu")
		(at 91.537028 -48.7426 180)
		(property "Reference" "R503"
			(at 0 0 180)
			(layer "F.SilkS")
			(hide yes)
			(effects
				(font
					(size 1.27 1.27)
				)
			)
		)
		(property "Value" "1MR2F-GP"
			(at 0.064008 -3.993896 180)
			(unlocked yes)
			(layer "F.Fab")
			(hide yes)
			(effects
				(font
					(size 1.016 1.016)
					(thickness 0.1524)
				)
			)
		)
		(property "Device Type" "R402H16"
			(at 0.064008 -5.517896 180)
			(unlocked yes)
			(layer "F.Fab")
			(hide yes)
			(effects
				(font
					(size 1.016 1.016)
					(thickness 0.1524)
				)
			)
		)
		(duplicate_pad_numbers_are_jumpers no)
		(fp_line
			(start 0.508 -0.9398)
			(end -0.508 -0.9398)
			(stroke
				(width 0.1524)
				(type default)
			)
			(layer "F.SilkS")
		)
		(fp_line
			(start -0.508 -0.9398)
			(end -0.508 0.9398)
			(stroke
				(width 0.1524)
				(type default)
			)
			(layer "F.SilkS")
		)
		(fp_rect
			(start -0.508 0.9398)
			(end 0.508 -0.9398)
			(stroke
				(width 0)
				(type default)
			)
			(fill no)
			(layer "F.CrtYd")
		)
		(fp_rect
			(start -0.508 0.9398)
			(end 0.508 -0.9398)
			(stroke
				(width 0)
				(type default)
			)
			(fill no)
			(layer "F.Fab")
		)
		(pad "1" smd custom
			(at 0 -0.4445 180)
			(size 0.1397 0.1397)
			(layers "F.Cu" "F.Mask" "F.Paste")
			(net "PQ2_D")
			(options
				(clearance outline)
				(anchor circle)
			)
			(primitives
				(gr_poly
					(pts
						(arc
							(start -0.1778 -0.2794)
							(mid -0.249642 -0.249642)
							(end -0.2794 -0.1778)
						)
						(arc
							(start -0.2794 0.1778)
							(mid -0.249642 0.249642)
							(end -0.1778 0.2794)
						)
						(arc
							(start 0.1778 0.2794)
							(mid 0.249642 0.249642)
							(end 0.2794 0.1778)
						)
						(arc
							(start 0.2794 -0.1778)
							(mid 0.249642 -0.249642)
							(end 0.1778 -0.2794)
						)
					)
					(width 0)
					(fill yes)
				)
			)
		)
		(pad "2" smd custom
			(at 0 0.4445 180)
			(size 0.1397 0.1397)
			(layers "F.Cu" "F.Mask" "F.Paste")
			(net "P12V_STBY")
			(options
				(clearance outline)
				(anchor circle)
			)
			(primitives
				(gr_poly
					(pts
						(arc
							(start -0.1778 -0.2794)
							(mid -0.249642 -0.249642)
							(end -0.2794 -0.1778)
						)
						(arc
							(start -0.2794 0.1778)
							(mid -0.249642 0.249642)
							(end -0.1778 0.2794)
						)
						(arc
							(start 0.1778 0.2794)
							(mid 0.249642 0.249642)
							(end 0.2794 0.1778)
						)
						(arc
							(start 0.2794 -0.1778)
							(mid 0.249642 -0.249642)
							(end 0.1778 -0.2794)
						)
					)
					(width 0)
					(fill yes)
				)
			)
		)
	)
	(footprint ""
		(layer "F.Cu")
		(at 53.773324 -162.481768 180)
		(property "Reference" "R412"
			(at 0 0 180)
			(layer "F.SilkS")
			(hide yes)
			(effects
				(font
					(size 1.27 1.27)
				)
			)
		)
		(property "Value" "1KR2F-3-GP"
			(at 0.064008 -3.993896 180)
			(unlocked yes)
			(layer "F.Fab")
			(hide yes)
			(effects
				(font
					(size 1.016 1.016)
					(thickness 0.1524)
				)
			)
		)
		(property "Device Type" "R402H16"
			(at 0.064008 -5.517896 180)
			(unlocked yes)
			(layer "F.Fab")
			(hide yes)
			(effects
				(font
					(size 1.016 1.016)
					(thickness 0.1524)
				)
			)
		)
		(duplicate_pad_numbers_are_jumpers no)
		(fp_line
			(start 0.508 -0.9398)
			(end -0.508 -0.9398)
			(stroke
				(width 0.1524)
				(type default)
			)
			(layer "F.SilkS")
		)
		(fp_line
			(start -0.508 -0.9398)
			(end -0.508 0.9398)
			(stroke
				(width 0.1524)
				(type default)
			)
			(layer "F.SilkS")
		)
		(fp_rect
			(start -0.508 0.9398)
			(end 0.508 -0.9398)
			(stroke
				(width 0)
				(type default)
			)
			(fill no)
			(layer "F.CrtYd")
		)
		(fp_rect
			(start -0.508 0.9398)
			(end 0.508 -0.9398)
			(stroke
				(width 0)
				(type default)
			)
			(fill no)
			(layer "F.Fab")
		)
		(pad "1" smd custom
			(at 0 -0.4445 180)
			(size 0.1397 0.1397)
			(layers "F.Cu" "F.Mask" "F.Paste")
			(net "ADC_P3V3")
			(options
				(clearance outline)
				(anchor circle)
			)
			(primitives
				(gr_poly
					(pts
						(arc
							(start -0.1778 -0.2794)
							(mid -0.249642 -0.249642)
							(end -0.2794 -0.1778)
						)
						(arc
							(start -0.2794 0.1778)
							(mid -0.249642 0.249642)
							(end -0.1778 0.2794)
						)
						(arc
							(start 0.1778 0.2794)
							(mid 0.249642 0.249642)
							(end 0.2794 0.1778)
						)
						(arc
							(start 0.2794 -0.1778)
							(mid 0.249642 -0.249642)
							(end 0.1778 -0.2794)
						)
					)
					(width 0)
					(fill yes)
				)
			)
		)
		(pad "2" smd custom
			(at 0 0.4445 180)
			(size 0.1397 0.1397)
			(layers "F.Cu" "F.Mask" "F.Paste")
			(net "GND")
			(options
				(clearance outline)
				(anchor circle)
			)
			(primitives
				(gr_poly
					(pts
						(arc
							(start -0.1778 -0.2794)
							(mid -0.249642 -0.249642)
							(end -0.2794 -0.1778)
						)
						(arc
							(start -0.2794 0.1778)
							(mid -0.249642 0.249642)
							(end -0.1778 0.2794)
						)
						(arc
							(start 0.1778 0.2794)
							(mid 0.249642 0.249642)
							(end 0.2794 0.1778)
						)
						(arc
							(start 0.2794 -0.1778)
							(mid 0.249642 -0.249642)
							(end 0.1778 -0.2794)
						)
					)
					(width 0)
					(fill yes)
				)
			)
		)
	)
	(footprint ""
		(layer "F.Cu")
		(at 111.139732 -14.262862 -90)
		(property "Reference" "R458"
			(at 0 0 270)
			(layer "F.SilkS")
			(hide yes)
			(effects
				(font
					(size 1.27 1.27)
				)
			)
		)
		(property "Value" "86K6R2F-GP"
			(at 0.064008 -3.993896 270)
			(unlocked yes)
			(layer "F.Fab")
			(hide yes)
			(effects
				(font
					(size 1.016 1.016)
					(thickness 0.1524)
				)
			)
		)
		(property "Device Type" "R402H16"
			(at 0.064008 -5.517896 270)
			(unlocked yes)
			(layer "F.Fab")
			(hide yes)
			(effects
				(font
					(size 1.016 1.016)
					(thickness 0.1524)
				)
			)
		)
		(duplicate_pad_numbers_are_jumpers no)
		(fp_line
			(start -0.508 -0.9398)
			(end -0.508 0.9398)
			(stroke
				(width 0.1524)
				(type default)
			)
			(layer "F.SilkS")
		)
		(fp_line
			(start 0.508 -0.9398)
			(end -0.508 -0.9398)
			(stroke
				(width 0.1524)
				(type default)
			)
			(layer "F.SilkS")
		)
		(fp_rect
			(start -0.508 0.9398)
			(end 0.508 -0.9398)
			(stroke
				(width 0)
				(type default)
			)
			(fill no)
			(layer "F.CrtYd")
		)
		(fp_rect
			(start -0.508 0.9398)
			(end 0.508 -0.9398)
			(stroke
				(width 0)
				(type default)
			)
			(fill no)
			(layer "F.Fab")
		)
		(pad "1" smd custom
			(at 0 -0.4445 270)
			(size 0.1397 0.1397)
			(layers "F.Cu" "F.Mask" "F.Paste")
			(net "MB0_PSET_R")
			(options
				(clearance outline)
				(anchor circle)
			)
			(primitives
				(gr_poly
					(pts
						(arc
							(start -0.1778 -0.2794)
							(mid -0.249642 -0.249642)
							(end -0.2794 -0.1778)
						)
						(arc
							(start -0.2794 0.1778)
							(mid -0.249642 0.249642)
							(end -0.1778 0.2794)
						)
						(arc
							(start 0.1778 0.2794)
							(mid 0.249642 0.249642)
							(end 0.2794 0.1778)
						)
						(arc
							(start 0.2794 -0.1778)
							(mid 0.249642 -0.249642)
							(end 0.1778 -0.2794)
						)
					)
					(width 0)
					(fill yes)
				)
			)
		)
		(pad "2" smd custom
			(at 0 0.4445 270)
			(size 0.1397 0.1397)
			(layers "F.Cu" "F.Mask" "F.Paste")
			(net "AGND_CURRENT_MON")
			(options
				(clearance outline)
				(anchor circle)
			)
			(primitives
				(gr_poly
					(pts
						(arc
							(start -0.1778 -0.2794)
							(mid -0.249642 -0.249642)
							(end -0.2794 -0.1778)
						)
						(arc
							(start -0.2794 0.1778)
							(mid -0.249642 0.249642)
							(end -0.1778 0.2794)
						)
						(arc
							(start 0.1778 0.2794)
							(mid 0.249642 0.249642)
							(end 0.2794 0.1778)
						)
						(arc
							(start 0.2794 -0.1778)
							(mid 0.249642 -0.249642)
							(end 0.1778 -0.2794)
						)
					)
					(width 0)
					(fill yes)
				)
			)
		)
	)
	(footprint ""
		(layer "F.Cu")
		(at 170.039538 -9.120378)
		(property "Reference" "C214"
			(at 0 0 0)
			(layer "F.SilkS")
			(hide yes)
			(effects
				(font
					(size 1.27 1.27)
				)
			)
		)
		(property "Value" "SCD1U16V2KX-3GP"
			(at 1.1811 -2.7051 0)
			(unlocked yes)
			(layer "F.Fab")
			(hide yes)
			(effects
				(font
					(size 1.016 1.016)
					(thickness 0.1524)
				)
			)
		)
		(property "Device Type" "C402H22"
			(at 1.1811 -4.2291 0)
			(unlocked yes)
			(layer "F.Fab")
			(hide yes)
			(effects
				(font
					(size 1.016 1.016)
					(thickness 0.1524)
				)
			)
		)
		(duplicate_pad_numbers_are_jumpers no)
		(fp_rect
			(start -0.4318 0.9525)
			(end 0.4318 -0.9525)
			(stroke
				(width 0)
				(type default)
			)
			(fill no)
			(layer "F.CrtYd")
		)
		(fp_rect
			(start -0.4318 0.9525)
			(end 0.4318 -0.9525)
			(stroke
				(width 0)
				(type default)
			)
			(fill no)
			(layer "F.Fab")
		)
		(pad "1" smd custom
			(at 0 -0.4445)
			(size 0.1524 0.1524)
			(layers "F.Cu" "F.Mask" "F.Paste")
			(net "P1V8_STBY")
			(options
				(clearance outline)
				(anchor circle)
			)
			(primitives
				(gr_poly
					(pts
						(arc
							(start 0.3048 -0.2032)
							(mid 0.275042 -0.275042)
							(end 0.2032 -0.3048)
						)
						(arc
							(start -0.2032 -0.3048)
							(mid -0.275042 -0.275042)
							(end -0.3048 -0.2032)
						)
						(arc
							(start -0.3048 0.2032)
							(mid -0.275042 0.275042)
							(end -0.2032 0.3048)
						)
						(arc
							(start 0.2032 0.3048)
							(mid 0.275042 0.275042)
							(end 0.3048 0.2032)
						)
					)
					(width 0)
					(fill yes)
				)
			)
		)
		(pad "2" smd custom
			(at 0 0.4445)
			(size 0.1524 0.1524)
			(layers "F.Cu" "F.Mask" "F.Paste")
			(net "GND")
			(options
				(clearance outline)
				(anchor circle)
			)
			(primitives
				(gr_poly
					(pts
						(arc
							(start 0.3048 -0.2032)
							(mid 0.275042 -0.275042)
							(end 0.2032 -0.3048)
						)
						(arc
							(start -0.2032 -0.3048)
							(mid -0.275042 -0.275042)
							(end -0.3048 -0.2032)
						)
						(arc
							(start -0.3048 0.2032)
							(mid -0.275042 0.275042)
							(end -0.2032 0.3048)
						)
						(arc
							(start 0.2032 0.3048)
							(mid 0.275042 0.275042)
							(end 0.3048 0.2032)
						)
					)
					(width 0)
					(fill yes)
				)
			)
		)
	)
)
